(kicad_pcb
	(version 20260206)
	(generator "pcbnew")
	(generator_version "10.0")
	(general
		(thickness 1.6)
		(legacy_teardrops no)
	)
	(paper "A4")
	(title_block
		(title "03242023_DA0F0TMBIJ0_F0T_Motherboard_J_brd_V01_OCP.brd")
		(comment 1 "Grand Teton / footprints 4871-4877 of 6105")
	)
	(layers
		(0 "F.Cu" signal "TOP")
		(4 "In1.Cu" signal "GND")
		(6 "In2.Cu" signal "IN1")
		(8 "In3.Cu" signal "GND1")
		(10 "In4.Cu" signal "IN2")
		(12 "In5.Cu" signal "GND2")
		(14 "In6.Cu" signal "IN3")
		(16 "In7.Cu" signal "GND3")
		(18 "In8.Cu" signal "VCC")
		(20 "In9.Cu" signal "VCC1")
		(22 "In10.Cu" signal "GND4")
		(24 "In11.Cu" signal "IN4")
		(26 "In12.Cu" signal "GND5")
		(28 "In13.Cu" signal "IN5")
		(30 "In14.Cu" signal "GND6")
		(32 "In15.Cu" signal "IN6")
		(34 "In16.Cu" signal "GND7")
		(2 "B.Cu" signal "BOTTOM")
		(9 "F.Adhes" user "F.Adhesive")
		(11 "B.Adhes" user "B.Adhesive")
		(13 "F.Paste" user "Package Geometry/Pastemask Top")
		(15 "B.Paste" user "Package Geometry/Pastemask Bottom")
		(5 "F.SilkS" user "Ref Des/Silkscreen Top")
		(7 "B.SilkS" user "Ref Des/Silkscreen Bottom")
		(1 "F.Mask" user "Board Geometry/Soldermask Top")
		(3 "B.Mask" user "Board Geometry/Soldermask Bottom")
		(17 "Dwgs.User" user "User.Drawings")
		(19 "Cmts.User" user "User.Comments")
		(21 "Eco1.User" user "User.Eco1")
		(23 "Eco2.User" user "User.Eco2")
		(25 "Edge.Cuts" user "Board Geometry/Outline")
		(27 "Margin" user)
		(31 "F.CrtYd" user "Package Geometry/Place Bound Top")
		(29 "B.CrtYd" user "Package Geometry/Place Bound Bottom")
		(35 "F.Fab" user "Ref Des/Assembly Top")
		(33 "B.Fab" user "Ref Des/Assembly Bottom")
	)
	(footprint ""
		(layer "B.Cu")
		(at 187.096654 -19.417792 -90)
		(property "Reference" "R2256"
			(at 0 0 90)
			(layer "B.SilkS")
			(hide yes)
			(effects
				(font
					(size 1.27 1.27)
				)
				(justify mirror)
			)
		)
		(property "Value" ""
			(at 0 0 90)
			(layer "B.Fab")
			(effects
				(font
					(size 1.27 1.27)
				)
				(justify mirror)
			)
		)
		(duplicate_pad_numbers_are_jumpers no)
		(fp_line
			(start -0.361696 0.4064)
			(end 0.522224 0.4064)
			(stroke
				(width 0.1524)
				(type default)
			)
			(layer "B.SilkS")
		)
		(fp_line
			(start 0.7874 0.137414)
			(end 0.7874 -0.4064)
			(stroke
				(width 0.1524)
				(type default)
			)
			(layer "B.SilkS")
		)
		(fp_line
			(start -0.7874 -0.4064)
			(end -0.7874 -0.055626)
			(stroke
				(width 0.1524)
				(type default)
			)
			(layer "B.SilkS")
		)
		(fp_line
			(start 0.7874 -0.4064)
			(end -0.7874 -0.4064)
			(stroke
				(width 0.1524)
				(type default)
			)
			(layer "B.SilkS")
		)
		(fp_line
			(start -0.67945 0.3048)
			(end -0.120396 0.3048)
			(stroke
				(width 0.1)
				(type default)
			)
			(layer "B.Fab")
		)
		(fp_line
			(start -0.120396 0.3048)
			(end -0.120396 0.2794)
			(stroke
				(width 0.1)
				(type default)
			)
			(layer "B.Fab")
		)
		(fp_line
			(start 0.12065 0.3048)
			(end 0.67945 0.3048)
			(stroke
				(width 0.1)
				(type default)
			)
			(layer "B.Fab")
		)
		(fp_line
			(start 0.67945 0.3048)
			(end 0.67945 -0.305054)
			(stroke
				(width 0.1)
				(type default)
			)
			(layer "B.Fab")
		)
		(fp_line
			(start -0.120396 0.2794)
			(end 0.12065 0.2794)
			(stroke
				(width 0.1)
				(type default)
			)
			(layer "B.Fab")
		)
		(fp_line
			(start 0.12065 0.2794)
			(end 0.12065 0.3048)
			(stroke
				(width 0.1)
				(type default)
			)
			(layer "B.Fab")
		)
		(fp_line
			(start -0.12065 -0.2794)
			(end -0.12065 -0.3048)
			(stroke
				(width 0.1)
				(type default)
			)
			(layer "B.Fab")
		)
		(fp_line
			(start 0.12065 -0.2794)
			(end -0.12065 -0.2794)
			(stroke
				(width 0.1)
				(type default)
			)
			(layer "B.Fab")
		)
		(fp_line
			(start -0.67945 -0.3048)
			(end -0.67945 0.3048)
			(stroke
				(width 0.1)
				(type default)
			)
			(layer "B.Fab")
		)
		(fp_line
			(start -0.12065 -0.3048)
			(end -0.67945 -0.3048)
			(stroke
				(width 0.1)
				(type default)
			)
			(layer "B.Fab")
		)
		(fp_line
			(start 0.12065 -0.305054)
			(end 0.12065 -0.2794)
			(stroke
				(width 0.1)
				(type default)
			)
			(layer "B.Fab")
		)
		(fp_line
			(start 0.67945 -0.305054)
			(end 0.12065 -0.305054)
			(stroke
				(width 0.1)
				(type default)
			)
			(layer "B.Fab")
		)
		(pad "1" smd circle
			(at 0.40005 0 90)
			(size 0 0)
			(layers "B.Cu" "B.Mask" "B.Paste")
			(net "USB2_7_R_DP")
		)
		(pad "2" smd circle
			(at -0.40005 0 90)
			(size 0 0)
			(layers "B.Cu" "B.Mask" "B.Paste")
			(net "USB2_7_DP")
		)
	)
	(footprint ""
		(layer "B.Cu")
		(at 169.66692 -53.431948 180)
		(property "Reference" "C1923"
			(at 0 0 0)
			(layer "B.SilkS")
			(hide yes)
			(effects
				(font
					(size 1.27 1.27)
				)
				(justify mirror)
			)
		)
		(property "Value" ""
			(at 0 0 0)
			(layer "B.Fab")
			(effects
				(font
					(size 1.27 1.27)
				)
				(justify mirror)
			)
		)
		(duplicate_pad_numbers_are_jumpers no)
		(fp_line
			(start 0.7874 0.4064)
			(end 0.7874 -0.4064)
			(stroke
				(width 0.1524)
				(type default)
			)
			(layer "B.SilkS")
		)
		(fp_line
			(start 0.7874 -0.4064)
			(end -0.7874 -0.4064)
			(stroke
				(width 0.1524)
				(type default)
			)
			(layer "B.SilkS")
		)
		(fp_line
			(start -0.7874 0.4064)
			(end 0.7874 0.4064)
			(stroke
				(width 0.1524)
				(type default)
			)
			(layer "B.SilkS")
		)
		(fp_line
			(start -0.7874 -0.4064)
			(end -0.7874 0.4064)
			(stroke
				(width 0.1524)
				(type default)
			)
			(layer "B.SilkS")
		)
		(fp_line
			(start 0.67945 0.3048)
			(end 0.67945 -0.305054)
			(stroke
				(width 0.1)
				(type default)
			)
			(layer "B.Fab")
		)
		(fp_line
			(start 0.67945 -0.305054)
			(end 0.12065 -0.305054)
			(stroke
				(width 0.1)
				(type default)
			)
			(layer "B.Fab")
		)
		(fp_line
			(start 0.12065 0.3048)
			(end 0.67945 0.3048)
			(stroke
				(width 0.1)
				(type default)
			)
			(layer "B.Fab")
		)
		(fp_line
			(start 0.12065 0.2794)
			(end 0.12065 0.3048)
			(stroke
				(width 0.1)
				(type default)
			)
			(layer "B.Fab")
		)
		(fp_line
			(start 0.12065 -0.2794)
			(end -0.12065 -0.2794)
			(stroke
				(width 0.1)
				(type default)
			)
			(layer "B.Fab")
		)
		(fp_line
			(start 0.12065 -0.305054)
			(end 0.12065 -0.2794)
			(stroke
				(width 0.1)
				(type default)
			)
			(layer "B.Fab")
		)
		(fp_line
			(start -0.120396 0.3048)
			(end -0.120396 0.2794)
			(stroke
				(width 0.1)
				(type default)
			)
			(layer "B.Fab")
		)
		(fp_line
			(start -0.120396 0.2794)
			(end 0.12065 0.2794)
			(stroke
				(width 0.1)
				(type default)
			)
			(layer "B.Fab")
		)
		(fp_line
			(start -0.12065 -0.2794)
			(end -0.12065 -0.3048)
			(stroke
				(width 0.1)
				(type default)
			)
			(layer "B.Fab")
		)
		(fp_line
			(start -0.12065 -0.3048)
			(end -0.67945 -0.3048)
			(stroke
				(width 0.1)
				(type default)
			)
			(layer "B.Fab")
		)
		(fp_line
			(start -0.67945 0.3048)
			(end -0.120396 0.3048)
			(stroke
				(width 0.1)
				(type default)
			)
			(layer "B.Fab")
		)
		(fp_line
			(start -0.67945 -0.3048)
			(end -0.67945 0.3048)
			(stroke
				(width 0.1)
				(type default)
			)
			(layer "B.Fab")
		)
		(pad "1" smd circle
			(at 0.40005 0)
			(size 0 0)
			(layers "B.Cu" "B.Mask" "B.Paste")
			(net "P3V3_M2_0")
		)
		(pad "2" smd circle
			(at -0.40005 0)
			(size 0 0)
			(layers "B.Cu" "B.Mask" "B.Paste")
			(net "GND")
		)
	)
	(footprint ""
		(layer "B.Cu")
		(at 48.666908 -193.25971 -90)
		(property "Reference" "R255"
			(at 0 0 90)
			(layer "B.SilkS")
			(hide yes)
			(effects
				(font
					(size 1.27 1.27)
				)
				(justify mirror)
			)
		)
		(property "Value" ""
			(at 0 0 90)
			(layer "B.Fab")
			(effects
				(font
					(size 1.27 1.27)
				)
				(justify mirror)
			)
		)
		(duplicate_pad_numbers_are_jumpers no)
		(fp_line
			(start -0.7874 0.4064)
			(end 0.7874 0.4064)
			(stroke
				(width 0.1524)
				(type default)
			)
			(layer "B.SilkS")
		)
		(fp_line
			(start 0.7874 0.4064)
			(end 0.7874 -0.4064)
			(stroke
				(width 0.1524)
				(type default)
			)
			(layer "B.SilkS")
		)
		(fp_line
			(start -0.7874 -0.4064)
			(end -0.7874 0.4064)
			(stroke
				(width 0.1524)
				(type default)
			)
			(layer "B.SilkS")
		)
		(fp_line
			(start 0.7874 -0.4064)
			(end -0.7874 -0.4064)
			(stroke
				(width 0.1524)
				(type default)
			)
			(layer "B.SilkS")
		)
		(fp_line
			(start -0.67945 0.3048)
			(end -0.120396 0.3048)
			(stroke
				(width 0.1)
				(type default)
			)
			(layer "B.Fab")
		)
		(fp_line
			(start -0.120396 0.3048)
			(end -0.120396 0.2794)
			(stroke
				(width 0.1)
				(type default)
			)
			(layer "B.Fab")
		)
		(fp_line
			(start 0.12065 0.3048)
			(end 0.67945 0.3048)
			(stroke
				(width 0.1)
				(type default)
			)
			(layer "B.Fab")
		)
		(fp_line
			(start 0.67945 0.3048)
			(end 0.67945 -0.305054)
			(stroke
				(width 0.1)
				(type default)
			)
			(layer "B.Fab")
		)
		(fp_line
			(start -0.120396 0.2794)
			(end 0.12065 0.2794)
			(stroke
				(width 0.1)
				(type default)
			)
			(layer "B.Fab")
		)
		(fp_line
			(start 0.12065 0.2794)
			(end 0.12065 0.3048)
			(stroke
				(width 0.1)
				(type default)
			)
			(layer "B.Fab")
		)
		(fp_line
			(start -0.12065 -0.2794)
			(end -0.12065 -0.3048)
			(stroke
				(width 0.1)
				(type default)
			)
			(layer "B.Fab")
		)
		(fp_line
			(start 0.12065 -0.2794)
			(end -0.12065 -0.2794)
			(stroke
				(width 0.1)
				(type default)
			)
			(layer "B.Fab")
		)
		(fp_line
			(start -0.67945 -0.3048)
			(end -0.67945 0.3048)
			(stroke
				(width 0.1)
				(type default)
			)
			(layer "B.Fab")
		)
		(fp_line
			(start -0.12065 -0.3048)
			(end -0.67945 -0.3048)
			(stroke
				(width 0.1)
				(type default)
			)
			(layer "B.Fab")
		)
		(fp_line
			(start 0.12065 -0.305054)
			(end 0.12065 -0.2794)
			(stroke
				(width 0.1)
				(type default)
			)
			(layer "B.Fab")
		)
		(fp_line
			(start 0.67945 -0.305054)
			(end 0.12065 -0.305054)
			(stroke
				(width 0.1)
				(type default)
			)
			(layer "B.Fab")
		)
		(pad "1" smd circle
			(at 0.40005 0 90)
			(size 0 0)
			(layers "B.Cu" "B.Mask" "B.Paste")
			(net "PVNN_TERM_CPU1")
		)
		(pad "2" smd circle
			(at -0.40005 0 90)
			(size 0 0)
			(layers "B.Cu" "B.Mask" "B.Paste")
			(net "FM_S3M_CPU1_LVC1_GPIO_0")
		)
	)
	(footprint ""
		(layer "B.Cu")
		(at 410.816044 -258.207764 -90)
		(property "Reference" "C514"
			(at 0 0 90)
			(layer "B.SilkS")
			(hide yes)
			(effects
				(font
					(size 1.27 1.27)
				)
				(justify mirror)
			)
		)
		(property "Value" ""
			(at 0 0 90)
			(layer "B.Fab")
			(effects
				(font
					(size 1.27 1.27)
				)
				(justify mirror)
			)
		)
		(duplicate_pad_numbers_are_jumpers no)
		(fp_line
			(start -1.524 0.762)
			(end 1.524 0.762)
			(stroke
				(width 0.1524)
				(type default)
			)
			(layer "B.SilkS")
		)
		(fp_line
			(start 1.524 0.762)
			(end 1.524 -0.762)
			(stroke
				(width 0.1524)
				(type default)
			)
			(layer "B.SilkS")
		)
		(fp_line
			(start -1.524 -0.762)
			(end -1.524 0.762)
			(stroke
				(width 0.1524)
				(type default)
			)
			(layer "B.SilkS")
		)
		(fp_line
			(start 1.524 -0.762)
			(end -1.524 -0.762)
			(stroke
				(width 0.1524)
				(type default)
			)
			(layer "B.SilkS")
		)
		(fp_line
			(start -1.1049 0.724916)
			(end -1.1049 -0.724916)
			(stroke
				(width 0.1)
				(type default)
			)
			(layer "B.Fab")
		)
		(fp_line
			(start 1.1049 0.724916)
			(end -1.1049 0.724916)
			(stroke
				(width 0.1)
				(type default)
			)
			(layer "B.Fab")
		)
		(fp_line
			(start -1.1049 -0.724916)
			(end 1.1049 -0.724916)
			(stroke
				(width 0.1)
				(type default)
			)
			(layer "B.Fab")
		)
		(fp_line
			(start 1.1049 -0.724916)
			(end 1.1049 0.724916)
			(stroke
				(width 0.1)
				(type default)
			)
			(layer "B.Fab")
		)
		(pad "1" smd rect
			(at 0.889 0 270)
			(size 1.016 1.27)
			(layers "B.Cu" "B.Mask" "B.Paste")
			(net "PVCCFA_EHV_FIVRA_CPU0")
		)
		(pad "2" smd rect
			(at -0.889 0 270)
			(size 1.016 1.27)
			(layers "B.Cu" "B.Mask" "B.Paste")
			(net "GND")
		)
	)
	(footprint ""
		(layer "B.Cu")
		(at 345.657932 -324.873366 -90)
		(property "Reference" "PC312_P0_1"
			(at 0 0 90)
			(layer "B.SilkS")
			(hide yes)
			(effects
				(font
					(size 1.27 1.27)
				)
				(justify mirror)
			)
		)
		(property "Value" ""
			(at 0 0 90)
			(layer "B.Fab")
			(effects
				(font
					(size 1.27 1.27)
				)
				(justify mirror)
			)
		)
		(duplicate_pad_numbers_are_jumpers no)
		(fp_line
			(start -1.524 0.762)
			(end 1.524 0.762)
			(stroke
				(width 0.1524)
				(type default)
			)
			(layer "B.SilkS")
		)
		(fp_line
			(start 1.524 0.762)
			(end 1.524 -0.762)
			(stroke
				(width 0.1524)
				(type default)
			)
			(layer "B.SilkS")
		)
		(fp_line
			(start -1.524 -0.762)
			(end -1.524 0.762)
			(stroke
				(width 0.1524)
				(type default)
			)
			(layer "B.SilkS")
		)
		(fp_line
			(start 1.524 -0.762)
			(end -1.524 -0.762)
			(stroke
				(width 0.1524)
				(type default)
			)
			(layer "B.SilkS")
		)
		(fp_line
			(start -1.1049 0.724916)
			(end -1.1049 -0.724916)
			(stroke
				(width 0.1)
				(type default)
			)
			(layer "B.Fab")
		)
		(fp_line
			(start 1.1049 0.724916)
			(end -1.1049 0.724916)
			(stroke
				(width 0.1)
				(type default)
			)
			(layer "B.Fab")
		)
		(fp_line
			(start -1.1049 -0.724916)
			(end 1.1049 -0.724916)
			(stroke
				(width 0.1)
				(type default)
			)
			(layer "B.Fab")
		)
		(fp_line
			(start 1.1049 -0.724916)
			(end 1.1049 0.724916)
			(stroke
				(width 0.1)
				(type default)
			)
			(layer "B.Fab")
		)
		(pad "1" smd rect
			(at 0.889 0 270)
			(size 1.016 1.27)
			(layers "B.Cu" "B.Mask" "B.Paste")
			(net "PVCCIN_CPU0")
		)
		(pad "2" smd rect
			(at -0.889 0 270)
			(size 1.016 1.27)
			(layers "B.Cu" "B.Mask" "B.Paste")
			(net "GND")
		)
	)
	(footprint ""
		(layer "B.Cu")
		(at 95.225108 -190.705232 90)
		(property "Reference" "R671"
			(at 0 0 90)
			(layer "B.SilkS")
			(hide yes)
			(effects
				(font
					(size 1.27 1.27)
				)
				(justify mirror)
			)
		)
		(property "Value" ""
			(at 0 0 90)
			(layer "B.Fab")
			(effects
				(font
					(size 1.27 1.27)
				)
				(justify mirror)
			)
		)
		(duplicate_pad_numbers_are_jumpers no)
		(fp_line
			(start 0.7874 -0.4064)
			(end -0.7874 -0.4064)
			(stroke
				(width 0.1524)
				(type default)
			)
			(layer "B.SilkS")
		)
		(fp_line
			(start -0.7874 -0.4064)
			(end -0.7874 0.4064)
			(stroke
				(width 0.1524)
				(type default)
			)
			(layer "B.SilkS")
		)
		(fp_line
			(start 0.7874 0.4064)
			(end 0.7874 -0.4064)
			(stroke
				(width 0.1524)
				(type default)
			)
			(layer "B.SilkS")
		)
		(fp_line
			(start -0.7874 0.4064)
			(end 0.7874 0.4064)
			(stroke
				(width 0.1524)
				(type default)
			)
			(layer "B.SilkS")
		)
		(fp_line
			(start 0.67945 -0.305054)
			(end 0.12065 -0.305054)
			(stroke
				(width 0.1)
				(type default)
			)
			(layer "B.Fab")
		)
		(fp_line
			(start 0.12065 -0.305054)
			(end 0.12065 -0.2794)
			(stroke
				(width 0.1)
				(type default)
			)
			(layer "B.Fab")
		)
		(fp_line
			(start -0.12065 -0.3048)
			(end -0.67945 -0.3048)
			(stroke
				(width 0.1)
				(type default)
			)
			(layer "B.Fab")
		)
		(fp_line
			(start -0.67945 -0.3048)
			(end -0.67945 0.3048)
			(stroke
				(width 0.1)
				(type default)
			)
			(layer "B.Fab")
		)
		(fp_line
			(start 0.12065 -0.2794)
			(end -0.12065 -0.2794)
			(stroke
				(width 0.1)
				(type default)
			)
			(layer "B.Fab")
		)
		(fp_line
			(start -0.12065 -0.2794)
			(end -0.12065 -0.3048)
			(stroke
				(width 0.1)
				(type default)
			)
			(layer "B.Fab")
		)
		(fp_line
			(start 0.12065 0.2794)
			(end 0.12065 0.3048)
			(stroke
				(width 0.1)
				(type default)
			)
			(layer "B.Fab")
		)
		(fp_line
			(start -0.120396 0.2794)
			(end 0.12065 0.2794)
			(stroke
				(width 0.1)
				(type default)
			)
			(layer "B.Fab")
		)
		(fp_line
			(start 0.67945 0.3048)
			(end 0.67945 -0.305054)
			(stroke
				(width 0.1)
				(type default)
			)
			(layer "B.Fab")
		)
		(fp_line
			(start 0.12065 0.3048)
			(end 0.67945 0.3048)
			(stroke
				(width 0.1)
				(type default)
			)
			(layer "B.Fab")
		)
		(fp_line
			(start -0.120396 0.3048)
			(end -0.120396 0.2794)
			(stroke
				(width 0.1)
				(type default)
			)
			(layer "B.Fab")
		)
		(fp_line
			(start -0.67945 0.3048)
			(end -0.120396 0.3048)
			(stroke
				(width 0.1)
				(type default)
			)
			(layer "B.Fab")
		)
		(pad "1" smd circle
			(at 0.40005 0 270)
			(size 0 0)
			(layers "B.Cu" "B.Mask" "B.Paste")
			(net "I3C_SPD_DDRABCD_CPU1_SDA")
		)
		(pad "2" smd circle
			(at -0.40005 0 270)
			(size 0 0)
			(layers "B.Cu" "B.Mask" "B.Paste")
			(net "I3C_SPD_DDRABCD_CPU1_R_SDA")
		)
	)
	(footprint ""
		(layer "B.Cu")
		(at 32.557212 -318.650112)
		(property "Reference" "R47"
			(at 0 0 0)
			(layer "B.SilkS")
			(hide yes)
			(effects
				(font
					(size 1.27 1.27)
				)
				(justify mirror)
			)
		)
		(property "Value" ""
			(at 0 0 0)
			(layer "B.Fab")
			(effects
				(font
					(size 1.27 1.27)
				)
				(justify mirror)
			)
		)
		(duplicate_pad_numbers_are_jumpers no)
		(fp_line
			(start -0.7874 -0.4064)
			(end -0.7874 0.4064)
			(stroke
				(width 0.1524)
				(type default)
			)
			(layer "B.SilkS")
		)
		(fp_line
			(start -0.7874 0.4064)
			(end 0.7874 0.4064)
			(stroke
				(width 0.1524)
				(type default)
			)
			(layer "B.SilkS")
		)
		(fp_line
			(start 0.7874 -0.4064)
			(end -0.7874 -0.4064)
			(stroke
				(width 0.1524)
				(type default)
			)
			(layer "B.SilkS")
		)
		(fp_line
			(start 0.7874 0.4064)
			(end 0.7874 -0.4064)
			(stroke
				(width 0.1524)
				(type default)
			)
			(layer "B.SilkS")
		)
		(fp_line
			(start -0.67945 -0.3048)
			(end -0.67945 0.3048)
			(stroke
				(width 0.1)
				(type default)
			)
			(layer "B.Fab")
		)
		(fp_line
			(start -0.67945 0.3048)
			(end -0.120396 0.3048)
			(stroke
				(width 0.1)
				(type default)
			)
			(layer "B.Fab")
		)
		(fp_line
			(start -0.12065 -0.3048)
			(end -0.67945 -0.3048)
			(stroke
				(width 0.1)
				(type default)
			)
			(layer "B.Fab")
		)
		(fp_line
			(start -0.12065 -0.2794)
			(end -0.12065 -0.3048)
			(stroke
				(width 0.1)
				(type default)
			)
			(layer "B.Fab")
		)
		(fp_line
			(start -0.120396 0.2794)
			(end 0.12065 0.2794)
			(stroke
				(width 0.1)
				(type default)
			)
			(layer "B.Fab")
		)
		(fp_line
			(start -0.120396 0.3048)
			(end -0.120396 0.2794)
			(stroke
				(width 0.1)
				(type default)
			)
			(layer "B.Fab")
		)
		(fp_line
			(start 0.12065 -0.305054)
			(end 0.12065 -0.2794)
			(stroke
				(width 0.1)
				(type default)
			)
			(layer "B.Fab")
		)
		(fp_line
			(start 0.12065 -0.2794)
			(end -0.12065 -0.2794)
			(stroke
				(width 0.1)
				(type default)
			)
			(layer "B.Fab")
		)
		(fp_line
			(start 0.12065 0.2794)
			(end 0.12065 0.3048)
			(stroke
				(width 0.1)
				(type default)
			)
			(layer "B.Fab")
		)
		(fp_line
			(start 0.12065 0.3048)
			(end 0.67945 0.3048)
			(stroke
				(width 0.1)
				(type default)
			)
			(layer "B.Fab")
		)
		(fp_line
			(start 0.67945 -0.305054)
			(end 0.12065 -0.305054)
			(stroke
				(width 0.1)
				(type default)
			)
			(layer "B.Fab")
		)
		(fp_line
			(start 0.67945 0.3048)
			(end 0.67945 -0.305054)
			(stroke
				(width 0.1)
				(type default)
			)
			(layer "B.Fab")
		)
		(pad "1" smd circle
			(at 0.40005 0 180)
			(size 0 0)
			(layers "B.Cu" "B.Mask" "B.Paste")
			(net "PD_CHC_CPU1_DIMM2_SAA")
		)
		(pad "2" smd circle
			(at -0.40005 0 180)
			(size 0 0)
			(layers "B.Cu" "B.Mask" "B.Paste")
			(net "GND")
		)
	)
)
